# T6G (Grand Teton) — schematic netlist excerpt (pin names and nets, part order shuffled) for the footprints in the layout excerpt that follows; sources: Cadence DE-HDL packaged netlist, KiCad conversion of 04192023_DAF0TMB3IC0_F0TG_MB_C_brd_V02_OCP.brd

R8032  Q_RES  0 5% CHIP  pkg 0402LF  page 81 : A = FM_ESPI_CPU0_ALERT_SEL ; B = FM_ESPI_CPU0_ALERT_R_SEL
R8064  Q_RES  0 5% CHIP  pkg 0402LF  page 200 : A = PVDDCR_CPU1_P0_OCP_N ; B = PVDDCR_CPU1_P0_OCP_N_R

(kicad_pcb
	(version 20260206)
	(generator "pcbnew")
	(generator_version "10.0")
	(general
		(thickness 1.6)
		(legacy_teardrops no)
	)
	(paper "A4")
	(title_block
		(title "04192023_DAF0TMB3IC0_F0TG_MB_C_brd_V02_OCP.brd")
		(comment 1 "Grand Teton / footprints 126-127 of 8354")
	)
	(layers
		(0 "F.Cu" signal "TOP")
		(4 "In1.Cu" signal "GND")
		(6 "In2.Cu" signal "IN1")
		(8 "In3.Cu" signal "GND1")
		(10 "In4.Cu" signal "IN2")
		(12 "In5.Cu" signal "GND2")
		(14 "In6.Cu" signal "IN3")
		(16 "In7.Cu" signal "GND3")
		(18 "In8.Cu" signal "VCC")
		(20 "In9.Cu" signal "VCC1")
		(22 "In10.Cu" signal "GND4")
		(24 "In11.Cu" signal "IN4")
		(26 "In12.Cu" signal "GND5")
		(28 "In13.Cu" signal "IN5")
		(30 "In14.Cu" signal "GND6")
		(32 "In15.Cu" signal "IN6")
		(34 "In16.Cu" signal "GND7")
		(2 "B.Cu" signal "BOTTOM")
		(9 "F.Adhes" user "F.Adhesive")
		(11 "B.Adhes" user "B.Adhesive")
		(13 "F.Paste" user "Package Geometry/Pastemask Top")
		(15 "B.Paste" user "Package Geometry/Pastemask Bottom")
		(5 "F.SilkS" user "Ref Des/Silkscreen Top")
		(7 "B.SilkS" user "Ref Des/Silkscreen Bottom")
		(1 "F.Mask" user "Board Geometry/Soldermask Top")
		(3 "B.Mask" user "Board Geometry/Soldermask Bottom")
		(17 "Dwgs.User" user "User.Drawings")
		(19 "Cmts.User" user "User.Comments")
		(21 "Eco1.User" user "User.Eco1")
		(23 "Eco2.User" user "User.Eco2")
		(25 "Edge.Cuts" user "Board Geometry/Outline")
		(27 "Margin" user)
		(31 "F.CrtYd" user "Package Geometry/Place Bound Top")
		(29 "B.CrtYd" user "Package Geometry/Place Bound Bottom")
		(35 "F.Fab" user "Ref Des/Assembly Top")
		(33 "B.Fab" user "Ref Des/Assembly Bottom")
	)
	(footprint ""
		(layer "F.Cu")
		(at 186.055 -137.668 90)
		(property "Reference" "R8032"
			(at 0 0 90)
			(layer "F.SilkS")
			(hide yes)
			(effects
				(font
					(size 1.27 1.27)
				)
			)
		)
		(property "Value" ""
			(at 0 0 90)
			(layer "F.Fab")
			(effects
				(font
					(size 1.27 1.27)
				)
			)
		)
		(duplicate_pad_numbers_are_jumpers no)
		(fp_line
			(start 0.7874 -0.4064)
			(end 0.7874 0.4064)
			(stroke
				(width 0.1524)
				(type default)
			)
			(layer "F.SilkS")
		)
		(fp_line
			(start -0.7874 -0.4064)
			(end 0.7874 -0.4064)
			(stroke
				(width 0.1524)
				(type default)
			)
			(layer "F.SilkS")
		)
		(fp_line
			(start 0.7874 0.4064)
			(end -0.7874 0.4064)
			(stroke
				(width 0.1524)
				(type default)
			)
			(layer "F.SilkS")
		)
		(fp_line
			(start -0.7874 0.4064)
			(end -0.7874 -0.4064)
			(stroke
				(width 0.1524)
				(type default)
			)
			(layer "F.SilkS")
		)
		(fp_line
			(start -0.12065 -0.305054)
			(end -0.12065 -0.2794)
			(stroke
				(width 0.1)
				(type default)
			)
			(layer "F.Fab")
		)
		(fp_line
			(start -0.67945 -0.305054)
			(end -0.12065 -0.305054)
			(stroke
				(width 0.1)
				(type default)
			)
			(layer "F.Fab")
		)
		(fp_line
			(start 0.67945 -0.3048)
			(end 0.67945 0.3048)
			(stroke
				(width 0.1)
				(type default)
			)
			(layer "F.Fab")
		)
		(fp_line
			(start 0.12065 -0.3048)
			(end 0.67945 -0.3048)
			(stroke
				(width 0.1)
				(type default)
			)
			(layer "F.Fab")
		)
		(fp_line
			(start 0.12065 -0.2794)
			(end 0.12065 -0.3048)
			(stroke
				(width 0.1)
				(type default)
			)
			(layer "F.Fab")
		)
		(fp_line
			(start -0.12065 -0.2794)
			(end 0.12065 -0.2794)
			(stroke
				(width 0.1)
				(type default)
			)
			(layer "F.Fab")
		)
		(fp_line
			(start 0.120396 0.2794)
			(end -0.12065 0.2794)
			(stroke
				(width 0.1)
				(type default)
			)
			(layer "F.Fab")
		)
		(fp_line
			(start -0.12065 0.2794)
			(end -0.12065 0.3048)
			(stroke
				(width 0.1)
				(type default)
			)
			(layer "F.Fab")
		)
		(fp_line
			(start 0.67945 0.3048)
			(end 0.120396 0.3048)
			(stroke
				(width 0.1)
				(type default)
			)
			(layer "F.Fab")
		)
		(fp_line
			(start 0.120396 0.3048)
			(end 0.120396 0.2794)
			(stroke
				(width 0.1)
				(type default)
			)
			(layer "F.Fab")
		)
		(fp_line
			(start -0.12065 0.3048)
			(end -0.67945 0.3048)
			(stroke
				(width 0.1)
				(type default)
			)
			(layer "F.Fab")
		)
		(fp_line
			(start -0.67945 0.3048)
			(end -0.67945 -0.305054)
			(stroke
				(width 0.1)
				(type default)
			)
			(layer "F.Fab")
		)
		(pad "1" smd circle
			(at -0.40005 0 90)
			(size 0 0)
			(layers "F.Cu" "F.Mask" "F.Paste")
			(net "FM_ESPI_CPU0_ALERT_SEL")
		)
		(pad "2" smd circle
			(at 0.40005 0 90)
			(size 0 0)
			(layers "F.Cu" "F.Mask" "F.Paste")
			(net "FM_ESPI_CPU0_ALERT_R_SEL")
		)
	)
	(footprint ""
		(layer "F.Cu")
		(at 316.738 -358.267 180)
		(property "Reference" "R8064"
			(at 0 0 180)
			(layer "F.SilkS")
			(hide yes)
			(effects
				(font
					(size 1.27 1.27)
				)
			)
		)
		(property "Value" ""
			(at 0 0 180)
			(layer "F.Fab")
			(effects
				(font
					(size 1.27 1.27)
				)
			)
		)
		(duplicate_pad_numbers_are_jumpers no)
		(fp_line
			(start 0.7874 0.4064)
			(end -0.7874 0.4064)
			(stroke
				(width 0.1524)
				(type default)
			)
			(layer "F.SilkS")
		)
		(fp_line
			(start 0.7874 -0.4064)
			(end 0.7874 0.4064)
			(stroke
				(width 0.1524)
				(type default)
			)
			(layer "F.SilkS")
		)
		(fp_line
			(start -0.7874 0.4064)
			(end -0.7874 -0.4064)
			(stroke
				(width 0.1524)
				(type default)
			)
			(layer "F.SilkS")
		)
		(fp_line
			(start -0.7874 -0.4064)
			(end 0.7874 -0.4064)
			(stroke
				(width 0.1524)
				(type default)
			)
			(layer "F.SilkS")
		)
		(fp_line
			(start 0.67945 0.3048)
			(end 0.120396 0.3048)
			(stroke
				(width 0.1)
				(type default)
			)
			(layer "F.Fab")
		)
		(fp_line
			(start 0.67945 -0.3048)
			(end 0.67945 0.3048)
			(stroke
				(width 0.1)
				(type default)
			)
			(layer "F.Fab")
		)
		(fp_line
			(start 0.12065 -0.2794)
			(end 0.12065 -0.3048)
			(stroke
				(width 0.1)
				(type default)
			)
			(layer "F.Fab")
		)
		(fp_line
			(start 0.12065 -0.3048)
			(end 0.67945 -0.3048)
			(stroke
				(width 0.1)
				(type default)
			)
			(layer "F.Fab")
		)
		(fp_line
			(start 0.120396 0.3048)
			(end 0.120396 0.2794)
			(stroke
				(width 0.1)
				(type default)
			)
			(layer "F.Fab")
		)
		(fp_line
			(start 0.120396 0.2794)
			(end -0.12065 0.2794)
			(stroke
				(width 0.1)
				(type default)
			)
			(layer "F.Fab")
		)
		(fp_line
			(start -0.12065 0.3048)
			(end -0.67945 0.3048)
			(stroke
				(width 0.1)
				(type default)
			)
			(layer "F.Fab")
		)
		(fp_line
			(start -0.12065 0.2794)
			(end -0.12065 0.3048)
			(stroke
				(width 0.1)
				(type default)
			)
			(layer "F.Fab")
		)
		(fp_line
			(start -0.12065 -0.2794)
			(end 0.12065 -0.2794)
			(stroke
				(width 0.1)
				(type default)
			)
			(layer "F.Fab")
		)
		(fp_line
			(start -0.12065 -0.305054)
			(end -0.12065 -0.2794)
			(stroke
				(width 0.1)
				(type default)
			)
			(layer "F.Fab")
		)
		(fp_line
			(start -0.67945 0.3048)
			(end -0.67945 -0.305054)
			(stroke
				(width 0.1)
				(type default)
			)
			(layer "F.Fab")
		)
		(fp_line
			(start -0.67945 -0.305054)
			(end -0.12065 -0.305054)
			(stroke
				(width 0.1)
				(type default)
			)
			(layer "F.Fab")
		)
		(pad "1" smd circle
			(at -0.40005 0 180)
			(size 0 0)
			(layers "F.Cu" "F.Mask" "F.Paste")
			(net "PVDDCR_CPU1_P0_OCP_N")
		)
		(pad "2" smd circle
			(at 0.40005 0 180)
			(size 0 0)
			(layers "F.Cu" "F.Mask" "F.Paste")
			(net "PVDDCR_CPU1_P0_OCP_N_R")
		)
	)
)
